M48
INCH,TZ
T01C.001
T02C.01
T03C.012
T04C.014
T05C.01417
T06C.016
T07C.02
T08C.028
T09C.02834
T10C.02913
T11C.119
T12C.138
T13C.14
T14C.166
T15C.168
T16C.225
T17C.037
T18C.053
T19C.086
T20C.087
T21C.093
T22C.094
T23C.097
T24C.111
T25C.404
;LEADER: 12 
;HEADER: 
;CODE  : ASCII 
;FILE  : 16315-1-bd-1-6.drl for backdrilling of board 16315-1.brd ... from layer 1 to layer 6
;T05 Holesize 1. = 14.170000 Tolerance = +0.000000/-0.000000 PLATED MILS Quantity = 128
%
G90
T05
X429724Y68307
Y73819
Y82481
Y87993
X436811Y91930
Y86418
Y77756
Y72245
X443898Y68307
Y73819
Y82481
Y87993
X450984Y91930
X458071Y87993
X450984Y86418
X458071Y82481
X450984Y77756
X458071Y73819
X450984Y72245
X458071Y68307
X465157Y72245
Y77756
Y86418
Y91930
X479331
X472244Y87993
X479331Y86418
X472244Y82481
X479331Y77756
X472244Y73819
X479331Y72245
X472244Y68307
X514764
Y73819
Y82481
Y87993
X521850Y91930
X528937Y87993
X521850Y86418
X528937Y82481
X521850Y77756
X528937Y73819
X521850Y72245
X528937Y68307
X536024Y72245
Y77756
Y86418
Y91930
X543110Y87993
Y82481
Y73819
Y68307
X557283
X550197Y72245
X557283Y73819
X550197Y77756
X557283Y82481
X550197Y86418
X557283Y87993
X550197Y91930
X564370
Y86418
Y77756
Y72245
X1398228Y68307
Y73819
Y82481
Y87993
X1405315Y91930
Y86418
Y77756
Y72245
X1412402Y68307
X1419488Y72245
X1412402Y73819
X1419488Y77756
X1412402Y82481
X1419488Y86418
X1412402Y87993
X1419488Y91930
X1426575Y87993
Y82481
Y73819
Y68307
X1433661Y72245
Y77756
Y86418
Y91930
X1447835
X1440748Y87993
X1447835Y86418
X1440748Y82481
X1447835Y77756
X1440748Y73819
X1447835Y72245
X1440748Y68307
X1483268
Y73819
Y82481
Y87993
X1490354Y91930
X1497441Y87993
X1490354Y86418
X1497441Y82481
X1490354Y77756
X1497441Y73819
X1490354Y72245
X1497441Y68307
X1504528Y72245
Y77756
Y86418
Y91930
X1518701
X1511614Y87993
X1518701Y86418
X1511614Y82481
X1518701Y77756
X1511614Y73819
X1518701Y72245
X1511614Y68307
X1525787
Y73819
Y82481
Y87993
X1532874Y91930
Y86418
Y77756
Y72245
M30
